#ISCELL
  mstr_misc dns *
  *
#ISCELL
  mstr_symbols cad_note *
  *
#ISCELL
  mstr_symbols design_note *
  *
#ISCELL
  mstr_symbols intel_corp_bpage *
  *
#ISCELL
  mstr_standard offpage *
  page238_i1
#ISCELL
  mstr_symbols gnd *
  page238_i13
#CELL
  mstr_discrete res *
  page238_i14
#ISCELL
  mstr_symbols gnd *
  page238_i15
#CELL
  mstr_discrete cap *
  page238_i19
#ISCELL
  mstr_symbols gnd *
  page238_i20
#CELL
  mstr_discrete res *
  page238_i21
#ISCELL
  mstr_symbols p3v3_stby *
  page238_i22
#CELL
  mstr_discrete cap *
  page238_i23
#ISCELL
  mstr_standard offpage *
  page238_i25
#ISCELL
  mstr_symbols gnd *
  page238_i27
#ISCELL
  mstr_symbols gnd *
  page238_i3
#CELL
  mstr_discrete cap *
  page238_i30
#CELL
  mstr_discrete cap *
  page238_i39
#ISCELL
  mstr_symbols gnd *
  page238_i4
#CELL
  mstr_vreg rt9059 *
  page238_i40
#CELL
  mstr_discrete res *
  page238_i41
#ISCELL
  mstr_symbols p3v3_stby *
  page238_i42
#ISCELL
  w_power w_vcc_circle *
  page238_i43
#ISCELL
  mstr_symbols p3v3_stby *
  page238_i44
#CELL
  w_hdl 4k42r2f-gp *
  page238_i45
#CELL
  mstr_discrete cap *
  page238_i5
#ISCELL
  mstr_symbols gnd *
  page238_i6
#CELL
  mstr_discrete cap *
  page238_i7
